(kicad_pcb
	(version 20260206)
	(generator "pcbnew")
	(generator_version "10.0")
	(general
		(thickness 1.6)
		(legacy_teardrops no)
	)
	(paper "A4")
	(title_block
		(title "01162023_DA0F0TEBIF0_F0T_Expander_BD_F_brd_V02_OCP.brd")
		(comment 1 "Grand Teton / footprints 3481-3486 of 9728")
	)
	(layers
		(0 "F.Cu" signal "TOP")
		(4 "In1.Cu" signal "GND")
		(6 "In2.Cu" signal "VCC")
		(8 "In3.Cu" signal "VCC1")
		(10 "In4.Cu" signal "GND1")
		(12 "In5.Cu" signal "IN1")
		(14 "In6.Cu" signal "GND2")
		(16 "In7.Cu" signal "IN2")
		(18 "In8.Cu" signal "GND3")
		(20 "In9.Cu" signal "IN3")
		(22 "In10.Cu" signal "GND4")
		(24 "In11.Cu" signal "IN4")
		(26 "In12.Cu" signal "GND5")
		(28 "In13.Cu" signal "IN5")
		(30 "In14.Cu" signal "GND6")
		(32 "In15.Cu" signal "IN6")
		(34 "In16.Cu" signal "GND7")
		(2 "B.Cu" signal "BOTTOM")
		(9 "F.Adhes" user "F.Adhesive")
		(11 "B.Adhes" user "B.Adhesive")
		(13 "F.Paste" user "Package Geometry/Pastemask Top")
		(15 "B.Paste" user "Package Geometry/Pastemask Bottom")
		(5 "F.SilkS" user "Ref Des/Silkscreen Top")
		(7 "B.SilkS" user "Ref Des/Silkscreen Bottom")
		(1 "F.Mask" user "Board Geometry/Soldermask Top")
		(3 "B.Mask" user "Board Geometry/Soldermask Bottom")
		(17 "Dwgs.User" user "User.Drawings")
		(19 "Cmts.User" user "User.Comments")
		(21 "Eco1.User" user "User.Eco1")
		(23 "Eco2.User" user "User.Eco2")
		(25 "Edge.Cuts" user "Board Geometry/Outline")
		(27 "Margin" user)
		(31 "F.CrtYd" user "Package Geometry/Place Bound Top")
		(29 "B.CrtYd" user "Package Geometry/Place Bound Bottom")
		(35 "F.Fab" user "Ref Des/Assembly Top")
		(33 "B.Fab" user "Ref Des/Assembly Bottom")
	)
	(footprint ""
		(layer "F.Cu")
		(at 279.459182 -402.338032 90)
		(property "Reference" "R1808"
			(at 0 0 90)
			(layer "F.SilkS")
			(hide yes)
			(effects
				(font
					(size 1.27 1.27)
				)
			)
		)
		(property "Value" ""
			(at 0 0 90)
			(layer "F.Fab")
			(effects
				(font
					(size 1.27 1.27)
				)
			)
		)
		(duplicate_pad_numbers_are_jumpers no)
		(fp_line
			(start 0.7874 -0.4064)
			(end 0.7874 0.4064)
			(stroke
				(width 0.1524)
				(type default)
			)
			(layer "F.SilkS")
		)
		(fp_line
			(start -0.7874 -0.4064)
			(end 0.7874 -0.4064)
			(stroke
				(width 0.1524)
				(type default)
			)
			(layer "F.SilkS")
		)
		(fp_line
			(start 0.7874 0.4064)
			(end -0.7874 0.4064)
			(stroke
				(width 0.1524)
				(type default)
			)
			(layer "F.SilkS")
		)
		(fp_line
			(start -0.7874 0.4064)
			(end -0.7874 -0.4064)
			(stroke
				(width 0.1524)
				(type default)
			)
			(layer "F.SilkS")
		)
		(fp_line
			(start -0.12065 -0.305054)
			(end -0.12065 -0.2794)
			(stroke
				(width 0.1)
				(type default)
			)
			(layer "F.Fab")
		)
		(fp_line
			(start -0.67945 -0.305054)
			(end -0.12065 -0.305054)
			(stroke
				(width 0.1)
				(type default)
			)
			(layer "F.Fab")
		)
		(fp_line
			(start 0.67945 -0.3048)
			(end 0.67945 0.3048)
			(stroke
				(width 0.1)
				(type default)
			)
			(layer "F.Fab")
		)
		(fp_line
			(start 0.12065 -0.3048)
			(end 0.67945 -0.3048)
			(stroke
				(width 0.1)
				(type default)
			)
			(layer "F.Fab")
		)
		(fp_line
			(start 0.12065 -0.2794)
			(end 0.12065 -0.3048)
			(stroke
				(width 0.1)
				(type default)
			)
			(layer "F.Fab")
		)
		(fp_line
			(start -0.12065 -0.2794)
			(end 0.12065 -0.2794)
			(stroke
				(width 0.1)
				(type default)
			)
			(layer "F.Fab")
		)
		(fp_line
			(start 0.120396 0.2794)
			(end -0.12065 0.2794)
			(stroke
				(width 0.1)
				(type default)
			)
			(layer "F.Fab")
		)
		(fp_line
			(start -0.12065 0.2794)
			(end -0.12065 0.3048)
			(stroke
				(width 0.1)
				(type default)
			)
			(layer "F.Fab")
		)
		(fp_line
			(start 0.67945 0.3048)
			(end 0.120396 0.3048)
			(stroke
				(width 0.1)
				(type default)
			)
			(layer "F.Fab")
		)
		(fp_line
			(start 0.120396 0.3048)
			(end 0.120396 0.2794)
			(stroke
				(width 0.1)
				(type default)
			)
			(layer "F.Fab")
		)
		(fp_line
			(start -0.12065 0.3048)
			(end -0.67945 0.3048)
			(stroke
				(width 0.1)
				(type default)
			)
			(layer "F.Fab")
		)
		(fp_line
			(start -0.67945 0.3048)
			(end -0.67945 -0.305054)
			(stroke
				(width 0.1)
				(type default)
			)
			(layer "F.Fab")
		)
		(pad "1" smd circle
			(at -0.40005 0 90)
			(size 0 0)
			(layers "F.Cu" "F.Mask" "F.Paste")
			(net "RST_MB_BIC_ISO_N")
		)
		(pad "2" smd circle
			(at 0.40005 0 90)
			(size 0 0)
			(layers "F.Cu" "F.Mask" "F.Paste")
			(net "RST_MB_BIC_ISO_R_N")
		)
	)
	(footprint ""
		(layer "F.Cu")
		(at 191.756538 -20.467574 180)
		(property "Reference" "R1675"
			(at 0 0 180)
			(layer "F.SilkS")
			(hide yes)
			(effects
				(font
					(size 1.27 1.27)
				)
			)
		)
		(property "Value" ""
			(at 0 0 180)
			(layer "F.Fab")
			(effects
				(font
					(size 1.27 1.27)
				)
			)
		)
		(duplicate_pad_numbers_are_jumpers no)
		(fp_line
			(start 0.7874 0.4064)
			(end -0.7874 0.4064)
			(stroke
				(width 0.1524)
				(type default)
			)
			(layer "F.SilkS")
		)
		(fp_line
			(start 0.7874 -0.4064)
			(end 0.7874 0.4064)
			(stroke
				(width 0.1524)
				(type default)
			)
			(layer "F.SilkS")
		)
		(fp_line
			(start -0.7874 0.4064)
			(end -0.7874 -0.4064)
			(stroke
				(width 0.1524)
				(type default)
			)
			(layer "F.SilkS")
		)
		(fp_line
			(start -0.7874 -0.4064)
			(end 0.7874 -0.4064)
			(stroke
				(width 0.1524)
				(type default)
			)
			(layer "F.SilkS")
		)
		(fp_line
			(start 0.67945 0.3048)
			(end 0.120396 0.3048)
			(stroke
				(width 0.1)
				(type default)
			)
			(layer "F.Fab")
		)
		(fp_line
			(start 0.67945 -0.3048)
			(end 0.67945 0.3048)
			(stroke
				(width 0.1)
				(type default)
			)
			(layer "F.Fab")
		)
		(fp_line
			(start 0.12065 -0.2794)
			(end 0.12065 -0.3048)
			(stroke
				(width 0.1)
				(type default)
			)
			(layer "F.Fab")
		)
		(fp_line
			(start 0.12065 -0.3048)
			(end 0.67945 -0.3048)
			(stroke
				(width 0.1)
				(type default)
			)
			(layer "F.Fab")
		)
		(fp_line
			(start 0.120396 0.3048)
			(end 0.120396 0.2794)
			(stroke
				(width 0.1)
				(type default)
			)
			(layer "F.Fab")
		)
		(fp_line
			(start 0.120396 0.2794)
			(end -0.12065 0.2794)
			(stroke
				(width 0.1)
				(type default)
			)
			(layer "F.Fab")
		)
		(fp_line
			(start -0.12065 0.3048)
			(end -0.67945 0.3048)
			(stroke
				(width 0.1)
				(type default)
			)
			(layer "F.Fab")
		)
		(fp_line
			(start -0.12065 0.2794)
			(end -0.12065 0.3048)
			(stroke
				(width 0.1)
				(type default)
			)
			(layer "F.Fab")
		)
		(fp_line
			(start -0.12065 -0.2794)
			(end 0.12065 -0.2794)
			(stroke
				(width 0.1)
				(type default)
			)
			(layer "F.Fab")
		)
		(fp_line
			(start -0.12065 -0.305054)
			(end -0.12065 -0.2794)
			(stroke
				(width 0.1)
				(type default)
			)
			(layer "F.Fab")
		)
		(fp_line
			(start -0.67945 0.3048)
			(end -0.67945 -0.305054)
			(stroke
				(width 0.1)
				(type default)
			)
			(layer "F.Fab")
		)
		(fp_line
			(start -0.67945 -0.305054)
			(end -0.12065 -0.305054)
			(stroke
				(width 0.1)
				(type default)
			)
			(layer "F.Fab")
		)
		(pad "1" smd circle
			(at -0.40005 0 180)
			(size 0 0)
			(layers "F.Cu" "F.Mask" "F.Paste")
			(net "P3V3_SSD6")
		)
		(pad "2" smd circle
			(at 0.40005 0 180)
			(size 0 0)
			(layers "F.Cu" "F.Mask" "F.Paste")
			(net "SMB_ISO_SSD6_SDA")
		)
	)
	(footprint ""
		(layer "F.Cu")
		(at 329.93838 -44.341542 90)
		(property "Reference" "C332"
			(at 0 0 90)
			(layer "F.SilkS")
			(hide yes)
			(effects
				(font
					(size 1.27 1.27)
				)
			)
		)
		(property "Value" ""
			(at 0 0 90)
			(layer "F.Fab")
			(effects
				(font
					(size 1.27 1.27)
				)
			)
		)
		(duplicate_pad_numbers_are_jumpers no)
		(fp_line
			(start 0.7874 -0.4064)
			(end 0.7874 0.4064)
			(stroke
				(width 0.1524)
				(type default)
			)
			(layer "F.SilkS")
		)
		(fp_line
			(start -0.7874 -0.4064)
			(end 0.7874 -0.4064)
			(stroke
				(width 0.1524)
				(type default)
			)
			(layer "F.SilkS")
		)
		(fp_line
			(start 0.7874 0.4064)
			(end -0.7874 0.4064)
			(stroke
				(width 0.1524)
				(type default)
			)
			(layer "F.SilkS")
		)
		(fp_line
			(start -0.7874 0.4064)
			(end -0.7874 -0.4064)
			(stroke
				(width 0.1524)
				(type default)
			)
			(layer "F.SilkS")
		)
		(fp_line
			(start -0.12065 -0.305054)
			(end -0.12065 -0.2794)
			(stroke
				(width 0.1)
				(type default)
			)
			(layer "F.Fab")
		)
		(fp_line
			(start -0.67945 -0.305054)
			(end -0.12065 -0.305054)
			(stroke
				(width 0.1)
				(type default)
			)
			(layer "F.Fab")
		)
		(fp_line
			(start 0.67945 -0.3048)
			(end 0.67945 0.3048)
			(stroke
				(width 0.1)
				(type default)
			)
			(layer "F.Fab")
		)
		(fp_line
			(start 0.12065 -0.3048)
			(end 0.67945 -0.3048)
			(stroke
				(width 0.1)
				(type default)
			)
			(layer "F.Fab")
		)
		(fp_line
			(start 0.12065 -0.2794)
			(end 0.12065 -0.3048)
			(stroke
				(width 0.1)
				(type default)
			)
			(layer "F.Fab")
		)
		(fp_line
			(start -0.12065 -0.2794)
			(end 0.12065 -0.2794)
			(stroke
				(width 0.1)
				(type default)
			)
			(layer "F.Fab")
		)
		(fp_line
			(start 0.120396 0.2794)
			(end -0.12065 0.2794)
			(stroke
				(width 0.1)
				(type default)
			)
			(layer "F.Fab")
		)
		(fp_line
			(start -0.12065 0.2794)
			(end -0.12065 0.3048)
			(stroke
				(width 0.1)
				(type default)
			)
			(layer "F.Fab")
		)
		(fp_line
			(start 0.67945 0.3048)
			(end 0.120396 0.3048)
			(stroke
				(width 0.1)
				(type default)
			)
			(layer "F.Fab")
		)
		(fp_line
			(start 0.120396 0.3048)
			(end 0.120396 0.2794)
			(stroke
				(width 0.1)
				(type default)
			)
			(layer "F.Fab")
		)
		(fp_line
			(start -0.12065 0.3048)
			(end -0.67945 0.3048)
			(stroke
				(width 0.1)
				(type default)
			)
			(layer "F.Fab")
		)
		(fp_line
			(start -0.67945 0.3048)
			(end -0.67945 -0.305054)
			(stroke
				(width 0.1)
				(type default)
			)
			(layer "F.Fab")
		)
		(pad "1" smd circle
			(at -0.40005 0 90)
			(size 0 0)
			(layers "F.Cu" "F.Mask" "F.Paste")
			(net "P12V_SSD11_VIN_P")
		)
		(pad "2" smd circle
			(at 0.40005 0 90)
			(size 0 0)
			(layers "F.Cu" "F.Mask" "F.Paste")
			(net "P12V_SSD11_VIN_N")
		)
	)
	(footprint ""
		(layer "F.Cu")
		(at 90.018108 -306.074572 90)
		(property "Reference" "R1237"
			(at 0 0 90)
			(layer "F.SilkS")
			(hide yes)
			(effects
				(font
					(size 1.27 1.27)
				)
			)
		)
		(property "Value" ""
			(at 0 0 90)
			(layer "F.Fab")
			(effects
				(font
					(size 1.27 1.27)
				)
			)
		)
		(duplicate_pad_numbers_are_jumpers no)
		(fp_line
			(start 0.7874 -0.4064)
			(end 0.7874 0.4064)
			(stroke
				(width 0.1524)
				(type default)
			)
			(layer "F.SilkS")
		)
		(fp_line
			(start -0.7874 -0.4064)
			(end 0.7874 -0.4064)
			(stroke
				(width 0.1524)
				(type default)
			)
			(layer "F.SilkS")
		)
		(fp_line
			(start 0.7874 0.4064)
			(end -0.7874 0.4064)
			(stroke
				(width 0.1524)
				(type default)
			)
			(layer "F.SilkS")
		)
		(fp_line
			(start -0.7874 0.4064)
			(end -0.7874 -0.4064)
			(stroke
				(width 0.1524)
				(type default)
			)
			(layer "F.SilkS")
		)
		(fp_line
			(start -0.12065 -0.305054)
			(end -0.12065 -0.2794)
			(stroke
				(width 0.1)
				(type default)
			)
			(layer "F.Fab")
		)
		(fp_line
			(start -0.67945 -0.305054)
			(end -0.12065 -0.305054)
			(stroke
				(width 0.1)
				(type default)
			)
			(layer "F.Fab")
		)
		(fp_line
			(start 0.67945 -0.3048)
			(end 0.67945 0.3048)
			(stroke
				(width 0.1)
				(type default)
			)
			(layer "F.Fab")
		)
		(fp_line
			(start 0.12065 -0.3048)
			(end 0.67945 -0.3048)
			(stroke
				(width 0.1)
				(type default)
			)
			(layer "F.Fab")
		)
		(fp_line
			(start 0.12065 -0.2794)
			(end 0.12065 -0.3048)
			(stroke
				(width 0.1)
				(type default)
			)
			(layer "F.Fab")
		)
		(fp_line
			(start -0.12065 -0.2794)
			(end 0.12065 -0.2794)
			(stroke
				(width 0.1)
				(type default)
			)
			(layer "F.Fab")
		)
		(fp_line
			(start 0.120396 0.2794)
			(end -0.12065 0.2794)
			(stroke
				(width 0.1)
				(type default)
			)
			(layer "F.Fab")
		)
		(fp_line
			(start -0.12065 0.2794)
			(end -0.12065 0.3048)
			(stroke
				(width 0.1)
				(type default)
			)
			(layer "F.Fab")
		)
		(fp_line
			(start 0.67945 0.3048)
			(end 0.120396 0.3048)
			(stroke
				(width 0.1)
				(type default)
			)
			(layer "F.Fab")
		)
		(fp_line
			(start 0.120396 0.3048)
			(end 0.120396 0.2794)
			(stroke
				(width 0.1)
				(type default)
			)
			(layer "F.Fab")
		)
		(fp_line
			(start -0.12065 0.3048)
			(end -0.67945 0.3048)
			(stroke
				(width 0.1)
				(type default)
			)
			(layer "F.Fab")
		)
		(fp_line
			(start -0.67945 0.3048)
			(end -0.67945 -0.305054)
			(stroke
				(width 0.1)
				(type default)
			)
			(layer "F.Fab")
		)
		(pad "1" smd circle
			(at -0.40005 0 90)
			(size 0 0)
			(layers "F.Cu" "F.Mask" "F.Paste")
			(net "PEX0_SPARE3")
		)
		(pad "2" smd circle
			(at 0.40005 0 90)
			(size 0 0)
			(layers "F.Cu" "F.Mask" "F.Paste")
			(net "P1V8_PEX")
		)
	)
	(footprint ""
		(layer "F.Cu")
		(at 82.7151 -59.546236 90)
		(property "Reference" "C2892"
			(at 0 0 90)
			(layer "F.SilkS")
			(hide yes)
			(effects
				(font
					(size 1.27 1.27)
				)
			)
		)
		(property "Value" ""
			(at 0 0 90)
			(layer "F.Fab")
			(effects
				(font
					(size 1.27 1.27)
				)
			)
		)
		(duplicate_pad_numbers_are_jumpers no)
		(fp_line
			(start 0.7874 -0.4064)
			(end 0.7874 0.4064)
			(stroke
				(width 0.1524)
				(type default)
			)
			(layer "F.SilkS")
		)
		(fp_line
			(start -0.7874 -0.4064)
			(end 0.7874 -0.4064)
			(stroke
				(width 0.1524)
				(type default)
			)
			(layer "F.SilkS")
		)
		(fp_line
			(start 0.7874 0.4064)
			(end -0.7874 0.4064)
			(stroke
				(width 0.1524)
				(type default)
			)
			(layer "F.SilkS")
		)
		(fp_line
			(start -0.7874 0.4064)
			(end -0.7874 -0.4064)
			(stroke
				(width 0.1524)
				(type default)
			)
			(layer "F.SilkS")
		)
		(fp_line
			(start -0.12065 -0.305054)
			(end -0.12065 -0.2794)
			(stroke
				(width 0.1)
				(type default)
			)
			(layer "F.Fab")
		)
		(fp_line
			(start -0.67945 -0.305054)
			(end -0.12065 -0.305054)
			(stroke
				(width 0.1)
				(type default)
			)
			(layer "F.Fab")
		)
		(fp_line
			(start 0.67945 -0.3048)
			(end 0.67945 0.3048)
			(stroke
				(width 0.1)
				(type default)
			)
			(layer "F.Fab")
		)
		(fp_line
			(start 0.12065 -0.3048)
			(end 0.67945 -0.3048)
			(stroke
				(width 0.1)
				(type default)
			)
			(layer "F.Fab")
		)
		(fp_line
			(start 0.12065 -0.2794)
			(end 0.12065 -0.3048)
			(stroke
				(width 0.1)
				(type default)
			)
			(layer "F.Fab")
		)
		(fp_line
			(start -0.12065 -0.2794)
			(end 0.12065 -0.2794)
			(stroke
				(width 0.1)
				(type default)
			)
			(layer "F.Fab")
		)
		(fp_line
			(start 0.120396 0.2794)
			(end -0.12065 0.2794)
			(stroke
				(width 0.1)
				(type default)
			)
			(layer "F.Fab")
		)
		(fp_line
			(start -0.12065 0.2794)
			(end -0.12065 0.3048)
			(stroke
				(width 0.1)
				(type default)
			)
			(layer "F.Fab")
		)
		(fp_line
			(start 0.67945 0.3048)
			(end 0.120396 0.3048)
			(stroke
				(width 0.1)
				(type default)
			)
			(layer "F.Fab")
		)
		(fp_line
			(start 0.120396 0.3048)
			(end 0.120396 0.2794)
			(stroke
				(width 0.1)
				(type default)
			)
			(layer "F.Fab")
		)
		(fp_line
			(start -0.12065 0.3048)
			(end -0.67945 0.3048)
			(stroke
				(width 0.1)
				(type default)
			)
			(layer "F.Fab")
		)
		(fp_line
			(start -0.67945 0.3048)
			(end -0.67945 -0.305054)
			(stroke
				(width 0.1)
				(type default)
			)
			(layer "F.Fab")
		)
		(pad "1" smd circle
			(at -0.40005 0 90)
			(size 0 0)
			(layers "F.Cu" "F.Mask" "F.Paste")
			(net "SSD3_AUX_P3V3_EN_R")
		)
		(pad "2" smd circle
			(at 0.40005 0 90)
			(size 0 0)
			(layers "F.Cu" "F.Mask" "F.Paste")
			(net "GND")
		)
	)
	(footprint ""
		(layer "F.Cu")
		(at 374.543828 -46.90491)
		(property "Reference" "R642"
			(at 0 0 0)
			(layer "F.SilkS")
			(hide yes)
			(effects
				(font
					(size 1.27 1.27)
				)
			)
		)
		(property "Value" ""
			(at 0 0 0)
			(layer "F.Fab")
			(effects
				(font
					(size 1.27 1.27)
				)
			)
		)
		(duplicate_pad_numbers_are_jumpers no)
		(fp_line
			(start -0.7874 -0.4064)
			(end 0.7874 -0.4064)
			(stroke
				(width 0.1524)
				(type default)
			)
			(layer "F.SilkS")
		)
		(fp_line
			(start -0.7874 0.4064)
			(end -0.7874 -0.4064)
			(stroke
				(width 0.1524)
				(type default)
			)
			(layer "F.SilkS")
		)
		(fp_line
			(start 0.7874 -0.4064)
			(end 0.7874 0.4064)
			(stroke
				(width 0.1524)
				(type default)
			)
			(layer "F.SilkS")
		)
		(fp_line
			(start 0.7874 0.4064)
			(end -0.7874 0.4064)
			(stroke
				(width 0.1524)
				(type default)
			)
			(layer "F.SilkS")
		)
		(fp_line
			(start -0.67945 -0.305054)
			(end -0.12065 -0.305054)
			(stroke
				(width 0.1)
				(type default)
			)
			(layer "F.Fab")
		)
		(fp_line
			(start -0.67945 0.3048)
			(end -0.67945 -0.305054)
			(stroke
				(width 0.1)
				(type default)
			)
			(layer "F.Fab")
		)
		(fp_line
			(start -0.12065 -0.305054)
			(end -0.12065 -0.2794)
			(stroke
				(width 0.1)
				(type default)
			)
			(layer "F.Fab")
		)
		(fp_line
			(start -0.12065 -0.2794)
			(end 0.12065 -0.2794)
			(stroke
				(width 0.1)
				(type default)
			)
			(layer "F.Fab")
		)
		(fp_line
			(start -0.12065 0.2794)
			(end -0.12065 0.3048)
			(stroke
				(width 0.1)
				(type default)
			)
			(layer "F.Fab")
		)
		(fp_line
			(start -0.12065 0.3048)
			(end -0.67945 0.3048)
			(stroke
				(width 0.1)
				(type default)
			)
			(layer "F.Fab")
		)
		(fp_line
			(start 0.120396 0.2794)
			(end -0.12065 0.2794)
			(stroke
				(width 0.1)
				(type default)
			)
			(layer "F.Fab")
		)
		(fp_line
			(start 0.120396 0.3048)
			(end 0.120396 0.2794)
			(stroke
				(width 0.1)
				(type default)
			)
			(layer "F.Fab")
		)
		(fp_line
			(start 0.12065 -0.3048)
			(end 0.67945 -0.3048)
			(stroke
				(width 0.1)
				(type default)
			)
			(layer "F.Fab")
		)
		(fp_line
			(start 0.12065 -0.2794)
			(end 0.12065 -0.3048)
			(stroke
				(width 0.1)
				(type default)
			)
			(layer "F.Fab")
		)
		(fp_line
			(start 0.67945 -0.3048)
			(end 0.67945 0.3048)
			(stroke
				(width 0.1)
				(type default)
			)
			(layer "F.Fab")
		)
		(fp_line
			(start 0.67945 0.3048)
			(end 0.120396 0.3048)
			(stroke
				(width 0.1)
				(type default)
			)
			(layer "F.Fab")
		)
		(pad "1" smd circle
			(at -0.40005 0)
			(size 0 0)
			(layers "F.Cu" "F.Mask" "F.Paste")
			(net "SSD12_ADC_ALERT_N")
		)
		(pad "2" smd circle
			(at 0.40005 0)
			(size 0 0)
			(layers "F.Cu" "F.Mask" "F.Paste")
			(net "SSD_8_15_ADC_ALERT_N")
		)
	)
)
